<schema xmlns="http://www.cadence.com/spb/csschema"
	xmlns:xsi="http://www.w3.org/2001/XMLSchema-instance"
	xsi:schemaLocation="http://www.cadence.com/spb/csschema CSSchema002.xsd">
  <header>
    <schemaVersion>16.5</schemaVersion>
    <creatorTool>conceptHDL</creatorTool>
    <modifierTool>conceptHDL</modifierTool>
    <modificationTime>2011-10-25T13:05:02</modificationTime>
    <savedLibrary>mstr_symbols</savedLibrary>
  </header>
  <designs>
    <design schemaType="nameBased" name="p12v" view="sch_1">
      <lastids>
        <netid>4</netid>
      </lastids>
      <cells>
      </cells>
      <nets>
        <net>
          <id>N1</id>
          <name>g</name>
          <scope>interface</scope>
          <direction>inout</direction>
        </net>
        <net>
          <id>N2</id>
          <name>page1_g</name>
        </net>
        <net>
          <id>N4</id>
          <name>page1_p12v</name>
        </net>
        <net>
          <id>N3</id>
          <name>p12v</name>
          <scope>global</scope>
        </net>
      </nets>
      <aliases>
        <alias net1="N2" lsb1="-1" msb1="-1" net2="N1" lsb2="-1" msb2="-1" />
        <alias net1="N4" lsb1="-1" msb1="-1" net2="N2" lsb2="-1" msb2="-1" />
        <alias net1="N4" lsb1="-1" msb1="-1" net2="N3" lsb2="-1" msb2="-1" />
      </aliases>
      <differentialnets>
      </differentialnets>
      <differentialbusnets>
      </differentialbusnets>
      <netgroups>
      </netgroups>
      <netinterfaces>
      </netinterfaces>
      <instances>
      </instances>
      <templateresolutions>
      </templateresolutions>
      <templateinstances>
      </templateinstances>
      <extensions>
        <extension name="schematic_extension">
        <schematicExtension>
        <netScopes>
          <netScope ref="g">
            <pageScope number="1">
              <scope>interface</scope>
              <direction>unknown</direction>
            </pageScope>
          </netScope>
          <netScope ref="p12v">
            <pageScope number="1">
              <scope>global</scope>
            </pageScope>
          </netScope>
        </netScopes>
        <pages>
          <page number="1">
            <physicalPageNumber>1</physicalPageNumber>
            <errorStatus>false</errorStatus>
            <nets>
              <net ref="g"></net>
              <net ref="p12v"></net>
            </nets>
            <instances>
            </instances>
          </page>
        </pages>
      </schematicExtension>
        </extension>
      </extensions>
    </design>
  </designs>
</schema>
